# T6G (Grand Teton) — schematic netlist excerpt (pin names and nets, part order shuffled) for the footprints in the layout excerpt that follows; sources: Cadence DE-HDL packaged netlist, KiCad conversion of 04192023_DAF0TMB3IC0_F0TG_MB_C_brd_V02_OCP.brd

R1310  Q_RES  4.7K 1% EMPTY  pkg 0402LF  page 357 : A = GND ; B = INA230_7_A0
C6011  Q_CAP  0.1UF 25V 10% X7R  pkg 0402  page 112 : A = BUF2_VDD ; B = GND

(kicad_pcb
	(version 20260206)
	(generator "pcbnew")
	(generator_version "10.0")
	(general
		(thickness 1.6)
		(legacy_teardrops no)
	)
	(paper "A4")
	(title_block
		(title "04192023_DAF0TMB3IC0_F0TG_MB_C_brd_V02_OCP.brd")
		(comment 1 "Grand Teton / footprints 4153-4154 of 8354")
	)
	(layers
		(0 "F.Cu" signal "TOP")
		(4 "In1.Cu" signal "GND")
		(6 "In2.Cu" signal "IN1")
		(8 "In3.Cu" signal "GND1")
		(10 "In4.Cu" signal "IN2")
		(12 "In5.Cu" signal "GND2")
		(14 "In6.Cu" signal "IN3")
		(16 "In7.Cu" signal "GND3")
		(18 "In8.Cu" signal "VCC")
		(20 "In9.Cu" signal "VCC1")
		(22 "In10.Cu" signal "GND4")
		(24 "In11.Cu" signal "IN4")
		(26 "In12.Cu" signal "GND5")
		(28 "In13.Cu" signal "IN5")
		(30 "In14.Cu" signal "GND6")
		(32 "In15.Cu" signal "IN6")
		(34 "In16.Cu" signal "GND7")
		(2 "B.Cu" signal "BOTTOM")
		(9 "F.Adhes" user "F.Adhesive")
		(11 "B.Adhes" user "B.Adhesive")
		(13 "F.Paste" user "Package Geometry/Pastemask Top")
		(15 "B.Paste" user "Package Geometry/Pastemask Bottom")
		(5 "F.SilkS" user "Ref Des/Silkscreen Top")
		(7 "B.SilkS" user "Ref Des/Silkscreen Bottom")
		(1 "F.Mask" user "Board Geometry/Soldermask Top")
		(3 "B.Mask" user "Board Geometry/Soldermask Bottom")
		(17 "Dwgs.User" user "User.Drawings")
		(19 "Cmts.User" user "User.Comments")
		(21 "Eco1.User" user "User.Eco1")
		(23 "Eco2.User" user "User.Eco2")
		(25 "Edge.Cuts" user "Board Geometry/Outline")
		(27 "Margin" user)
		(31 "F.CrtYd" user "Package Geometry/Place Bound Top")
		(29 "B.CrtYd" user "Package Geometry/Place Bound Bottom")
		(35 "F.Fab" user "Ref Des/Assembly Top")
		(33 "B.Fab" user "Ref Des/Assembly Bottom")
	)
	(footprint ""
		(layer "F.Cu")
		(at 19.241516 -39.926514)
		(property "Reference" "R1310"
			(at 0 0 0)
			(layer "F.SilkS")
			(hide yes)
			(effects
				(font
					(size 1.27 1.27)
				)
			)
		)
		(property "Value" ""
			(at 0 0 0)
			(layer "F.Fab")
			(effects
				(font
					(size 1.27 1.27)
				)
			)
		)
		(duplicate_pad_numbers_are_jumpers no)
		(fp_line
			(start -0.7874 -0.4064)
			(end 0.7874 -0.4064)
			(stroke
				(width 0.1524)
				(type default)
			)
			(layer "F.SilkS")
		)
		(fp_line
			(start -0.7874 0.4064)
			(end -0.7874 -0.4064)
			(stroke
				(width 0.1524)
				(type default)
			)
			(layer "F.SilkS")
		)
		(fp_line
			(start 0.7874 -0.4064)
			(end 0.7874 0.4064)
			(stroke
				(width 0.1524)
				(type default)
			)
			(layer "F.SilkS")
		)
		(fp_line
			(start 0.7874 0.4064)
			(end -0.7874 0.4064)
			(stroke
				(width 0.1524)
				(type default)
			)
			(layer "F.SilkS")
		)
		(fp_line
			(start -0.67945 -0.305054)
			(end -0.12065 -0.305054)
			(stroke
				(width 0.1)
				(type default)
			)
			(layer "F.Fab")
		)
		(fp_line
			(start -0.67945 0.3048)
			(end -0.67945 -0.305054)
			(stroke
				(width 0.1)
				(type default)
			)
			(layer "F.Fab")
		)
		(fp_line
			(start -0.12065 -0.305054)
			(end -0.12065 -0.2794)
			(stroke
				(width 0.1)
				(type default)
			)
			(layer "F.Fab")
		)
		(fp_line
			(start -0.12065 -0.2794)
			(end 0.12065 -0.2794)
			(stroke
				(width 0.1)
				(type default)
			)
			(layer "F.Fab")
		)
		(fp_line
			(start -0.12065 0.2794)
			(end -0.12065 0.3048)
			(stroke
				(width 0.1)
				(type default)
			)
			(layer "F.Fab")
		)
		(fp_line
			(start -0.12065 0.3048)
			(end -0.67945 0.3048)
			(stroke
				(width 0.1)
				(type default)
			)
			(layer "F.Fab")
		)
		(fp_line
			(start 0.120396 0.2794)
			(end -0.12065 0.2794)
			(stroke
				(width 0.1)
				(type default)
			)
			(layer "F.Fab")
		)
		(fp_line
			(start 0.120396 0.3048)
			(end 0.120396 0.2794)
			(stroke
				(width 0.1)
				(type default)
			)
			(layer "F.Fab")
		)
		(fp_line
			(start 0.12065 -0.3048)
			(end 0.67945 -0.3048)
			(stroke
				(width 0.1)
				(type default)
			)
			(layer "F.Fab")
		)
		(fp_line
			(start 0.12065 -0.2794)
			(end 0.12065 -0.3048)
			(stroke
				(width 0.1)
				(type default)
			)
			(layer "F.Fab")
		)
		(fp_line
			(start 0.67945 -0.3048)
			(end 0.67945 0.3048)
			(stroke
				(width 0.1)
				(type default)
			)
			(layer "F.Fab")
		)
		(fp_line
			(start 0.67945 0.3048)
			(end 0.120396 0.3048)
			(stroke
				(width 0.1)
				(type default)
			)
			(layer "F.Fab")
		)
		(pad "1" smd circle
			(at -0.40005 0)
			(size 0 0)
			(layers "F.Cu" "F.Mask" "F.Paste")
			(net "GND")
		)
		(pad "2" smd circle
			(at 0.40005 0)
			(size 0 0)
			(layers "F.Cu" "F.Mask" "F.Paste")
			(net "INA230_7_A0")
		)
	)
	(footprint ""
		(layer "F.Cu")
		(at 21.702268 -423.450258)
		(property "Reference" "C6011"
			(at 0 0 0)
			(layer "F.SilkS")
			(hide yes)
			(effects
				(font
					(size 1.27 1.27)
				)
			)
		)
		(property "Value" ""
			(at 0 0 0)
			(layer "F.Fab")
			(effects
				(font
					(size 1.27 1.27)
				)
			)
		)
		(duplicate_pad_numbers_are_jumpers no)
		(fp_line
			(start -0.7874 -0.4064)
			(end 0.7874 -0.4064)
			(stroke
				(width 0.1524)
				(type default)
			)
			(layer "F.SilkS")
		)
		(fp_line
			(start -0.7874 0.4064)
			(end -0.7874 -0.4064)
			(stroke
				(width 0.1524)
				(type default)
			)
			(layer "F.SilkS")
		)
		(fp_line
			(start 0.7874 -0.4064)
			(end 0.7874 0.4064)
			(stroke
				(width 0.1524)
				(type default)
			)
			(layer "F.SilkS")
		)
		(fp_line
			(start 0.7874 0.4064)
			(end -0.7874 0.4064)
			(stroke
				(width 0.1524)
				(type default)
			)
			(layer "F.SilkS")
		)
		(fp_line
			(start -0.67945 -0.305054)
			(end -0.12065 -0.305054)
			(stroke
				(width 0.1)
				(type default)
			)
			(layer "F.Fab")
		)
		(fp_line
			(start -0.67945 0.3048)
			(end -0.67945 -0.305054)
			(stroke
				(width 0.1)
				(type default)
			)
			(layer "F.Fab")
		)
		(fp_line
			(start -0.12065 -0.305054)
			(end -0.12065 -0.2794)
			(stroke
				(width 0.1)
				(type default)
			)
			(layer "F.Fab")
		)
		(fp_line
			(start -0.12065 -0.2794)
			(end 0.12065 -0.2794)
			(stroke
				(width 0.1)
				(type default)
			)
			(layer "F.Fab")
		)
		(fp_line
			(start -0.12065 0.2794)
			(end -0.12065 0.3048)
			(stroke
				(width 0.1)
				(type default)
			)
			(layer "F.Fab")
		)
		(fp_line
			(start -0.12065 0.3048)
			(end -0.67945 0.3048)
			(stroke
				(width 0.1)
				(type default)
			)
			(layer "F.Fab")
		)
		(fp_line
			(start 0.120396 0.2794)
			(end -0.12065 0.2794)
			(stroke
				(width 0.1)
				(type default)
			)
			(layer "F.Fab")
		)
		(fp_line
			(start 0.120396 0.3048)
			(end 0.120396 0.2794)
			(stroke
				(width 0.1)
				(type default)
			)
			(layer "F.Fab")
		)
		(fp_line
			(start 0.12065 -0.3048)
			(end 0.67945 -0.3048)
			(stroke
				(width 0.1)
				(type default)
			)
			(layer "F.Fab")
		)
		(fp_line
			(start 0.12065 -0.2794)
			(end 0.12065 -0.3048)
			(stroke
				(width 0.1)
				(type default)
			)
			(layer "F.Fab")
		)
		(fp_line
			(start 0.67945 -0.3048)
			(end 0.67945 0.3048)
			(stroke
				(width 0.1)
				(type default)
			)
			(layer "F.Fab")
		)
		(fp_line
			(start 0.67945 0.3048)
			(end 0.120396 0.3048)
			(stroke
				(width 0.1)
				(type default)
			)
			(layer "F.Fab")
		)
		(pad "1" smd circle
			(at -0.40005 0)
			(size 0 0)
			(layers "F.Cu" "F.Mask" "F.Paste")
			(net "BUF2_VDD")
		)
		(pad "2" smd circle
			(at 0.40005 0)
			(size 0 0)
			(layers "F.Cu" "F.Mask" "F.Paste")
			(net "GND")
		)
	)
)
